(kicad_pcb
	(version 20260206)
	(generator "pcbnew")
	(generator_version "10.0")
	(general
		(thickness 1.6)
		(legacy_teardrops no)
	)
	(paper "A4")
	(title_block
		(title "04192023_DAF0TMB3IC0_F0TG_MB_C_brd_V02_OCP.brd")
		(comment 1 "Grand Teton / footprints 3698-3702 of 8354")
	)
	(layers
		(0 "F.Cu" signal "TOP")
		(4 "In1.Cu" signal "GND")
		(6 "In2.Cu" signal "IN1")
		(8 "In3.Cu" signal "GND1")
		(10 "In4.Cu" signal "IN2")
		(12 "In5.Cu" signal "GND2")
		(14 "In6.Cu" signal "IN3")
		(16 "In7.Cu" signal "GND3")
		(18 "In8.Cu" signal "VCC")
		(20 "In9.Cu" signal "VCC1")
		(22 "In10.Cu" signal "GND4")
		(24 "In11.Cu" signal "IN4")
		(26 "In12.Cu" signal "GND5")
		(28 "In13.Cu" signal "IN5")
		(30 "In14.Cu" signal "GND6")
		(32 "In15.Cu" signal "IN6")
		(34 "In16.Cu" signal "GND7")
		(2 "B.Cu" signal "BOTTOM")
		(9 "F.Adhes" user "F.Adhesive")
		(11 "B.Adhes" user "B.Adhesive")
		(13 "F.Paste" user "Package Geometry/Pastemask Top")
		(15 "B.Paste" user "Package Geometry/Pastemask Bottom")
		(5 "F.SilkS" user "Ref Des/Silkscreen Top")
		(7 "B.SilkS" user "Ref Des/Silkscreen Bottom")
		(1 "F.Mask" user "Board Geometry/Soldermask Top")
		(3 "B.Mask" user "Board Geometry/Soldermask Bottom")
		(17 "Dwgs.User" user "User.Drawings")
		(19 "Cmts.User" user "User.Comments")
		(21 "Eco1.User" user "User.Eco1")
		(23 "Eco2.User" user "User.Eco2")
		(25 "Edge.Cuts" user "Board Geometry/Outline")
		(27 "Margin" user)
		(31 "F.CrtYd" user "Package Geometry/Place Bound Top")
		(29 "B.CrtYd" user "Package Geometry/Place Bound Bottom")
		(35 "F.Fab" user "Ref Des/Assembly Top")
		(33 "B.Fab" user "Ref Des/Assembly Bottom")
	)
	(footprint ""
		(layer "F.Cu")
		(at 187.833 -96.103948 -90)
		(property "Reference" "R1036"
			(at 0 0 270)
			(layer "F.SilkS")
			(hide yes)
			(effects
				(font
					(size 1.27 1.27)
				)
			)
		)
		(property "Value" ""
			(at 0 0 270)
			(layer "F.Fab")
			(effects
				(font
					(size 1.27 1.27)
				)
			)
		)
		(duplicate_pad_numbers_are_jumpers no)
		(fp_line
			(start -0.7874 0.4064)
			(end -0.7874 -0.4064)
			(stroke
				(width 0.1524)
				(type default)
			)
			(layer "F.SilkS")
		)
		(fp_line
			(start 0.7874 0.4064)
			(end -0.7874 0.4064)
			(stroke
				(width 0.1524)
				(type default)
			)
			(layer "F.SilkS")
		)
		(fp_line
			(start -0.7874 -0.4064)
			(end 0.7874 -0.4064)
			(stroke
				(width 0.1524)
				(type default)
			)
			(layer "F.SilkS")
		)
		(fp_line
			(start 0.7874 -0.4064)
			(end 0.7874 0.4064)
			(stroke
				(width 0.1524)
				(type default)
			)
			(layer "F.SilkS")
		)
		(fp_line
			(start -0.67945 0.3048)
			(end -0.67945 -0.305054)
			(stroke
				(width 0.1)
				(type default)
			)
			(layer "F.Fab")
		)
		(fp_line
			(start -0.12065 0.3048)
			(end -0.67945 0.3048)
			(stroke
				(width 0.1)
				(type default)
			)
			(layer "F.Fab")
		)
		(fp_line
			(start 0.120396 0.3048)
			(end 0.120396 0.2794)
			(stroke
				(width 0.1)
				(type default)
			)
			(layer "F.Fab")
		)
		(fp_line
			(start 0.67945 0.3048)
			(end 0.120396 0.3048)
			(stroke
				(width 0.1)
				(type default)
			)
			(layer "F.Fab")
		)
		(fp_line
			(start -0.12065 0.2794)
			(end -0.12065 0.3048)
			(stroke
				(width 0.1)
				(type default)
			)
			(layer "F.Fab")
		)
		(fp_line
			(start 0.120396 0.2794)
			(end -0.12065 0.2794)
			(stroke
				(width 0.1)
				(type default)
			)
			(layer "F.Fab")
		)
		(fp_line
			(start -0.12065 -0.2794)
			(end 0.12065 -0.2794)
			(stroke
				(width 0.1)
				(type default)
			)
			(layer "F.Fab")
		)
		(fp_line
			(start 0.12065 -0.2794)
			(end 0.12065 -0.3048)
			(stroke
				(width 0.1)
				(type default)
			)
			(layer "F.Fab")
		)
		(fp_line
			(start 0.12065 -0.3048)
			(end 0.67945 -0.3048)
			(stroke
				(width 0.1)
				(type default)
			)
			(layer "F.Fab")
		)
		(fp_line
			(start 0.67945 -0.3048)
			(end 0.67945 0.3048)
			(stroke
				(width 0.1)
				(type default)
			)
			(layer "F.Fab")
		)
		(fp_line
			(start -0.67945 -0.305054)
			(end -0.12065 -0.305054)
			(stroke
				(width 0.1)
				(type default)
			)
			(layer "F.Fab")
		)
		(fp_line
			(start -0.12065 -0.305054)
			(end -0.12065 -0.2794)
			(stroke
				(width 0.1)
				(type default)
			)
			(layer "F.Fab")
		)
		(pad "1" smd circle
			(at -0.40005 0 270)
			(size 0 0)
			(layers "F.Cu" "F.Mask" "F.Paste")
			(net "FM_SMB_RST_E1S_0_N")
		)
		(pad "2" smd circle
			(at 0.40005 0 270)
			(size 0 0)
			(layers "F.Cu" "F.Mask" "F.Paste")
			(net "FM_SMB_RST_E1S_0_R_N")
		)
	)
	(footprint ""
		(layer "F.Cu")
		(at 495.90833 -147.933918 -90)
		(property "Reference" "X4"
			(at -1.809496 3.220974 0)
			(unlocked yes)
			(layer "F.SilkS")
			(effects
				(font
					(size 0.7874 0.5842)
					(thickness 0.1524)
				)
				(justify left)
			)
		)
		(property "Value" ""
			(at 0 0 270)
			(layer "F.Fab")
			(effects
				(font
					(size 1.27 1.27)
				)
			)
		)
		(property "Device Type" "TP_TDR_4P_FTS_TH-TP_TDR_4P_DIP,EMPTY,TP15"
			(at 1.30175 1.27 0)
			(unlocked yes)
			(layer "F.Fab")
			(hide yes)
			(effects
				(font
					(size 0.635 0.4064)
					(thickness 0.1524)
				)
			)
		)
		(property "User Part Number" "N_A"
			(at 1.30175 1.27 0)
			(unlocked yes)
			(layer "Cmts.User")
			(hide yes)
			(effects
				(font
					(size 0.635 0.4064)
					(thickness 0.1524)
				)
			)
		)
		(duplicate_pad_numbers_are_jumpers no)
		(fp_line
			(start 0 3.81)
			(end 2.54 3.81)
			(stroke
				(width 0.1524)
				(type default)
			)
			(layer "F.SilkS")
		)
		(fp_line
			(start 2.54 3.81)
			(end 2.54 3.6703)
			(stroke
				(width 0.1524)
				(type default)
			)
			(layer "F.SilkS")
		)
		(fp_line
			(start 0 3.175)
			(end 0 3.81)
			(stroke
				(width 0.1524)
				(type default)
			)
			(layer "F.SilkS")
		)
		(fp_line
			(start 2.54 1.4097)
			(end 2.54 1.1303)
			(stroke
				(width 0.1524)
				(type default)
			)
			(layer "F.SilkS")
		)
		(fp_line
			(start 0 0.635)
			(end 0 1.905)
			(stroke
				(width 0.1524)
				(type default)
			)
			(layer "F.SilkS")
		)
		(fp_line
			(start 2.54 -1.1303)
			(end 2.54 -1.27)
			(stroke
				(width 0.1524)
				(type default)
			)
			(layer "F.SilkS")
		)
		(fp_line
			(start 0 -1.27)
			(end 0 -0.635)
			(stroke
				(width 0.1524)
				(type default)
			)
			(layer "F.SilkS")
		)
		(fp_line
			(start 2.54 -1.27)
			(end 0 -1.27)
			(stroke
				(width 0.1524)
				(type default)
			)
			(layer "F.SilkS")
		)
		(fp_poly
			(pts
				(xy -0.761746 0) (xy -2.285746 0.762) (xy -2.285746 -0.762)
			)
			(stroke
				(width 0)
				(type default)
			)
			(fill yes)
			(layer "F.SilkS")
		)
		(fp_line
			(start 0 3.81)
			(end 2.54 3.81)
			(stroke
				(width 0.1)
				(type default)
			)
			(layer "F.Fab")
		)
		(fp_line
			(start 2.54 3.81)
			(end 2.54 -1.27)
			(stroke
				(width 0.1)
				(type default)
			)
			(layer "F.Fab")
		)
		(fp_line
			(start 0 -1.27)
			(end 0 3.81)
			(stroke
				(width 0.1)
				(type default)
			)
			(layer "F.Fab")
		)
		(fp_line
			(start 2.54 -1.27)
			(end 0 -1.27)
			(stroke
				(width 0.1)
				(type default)
			)
			(layer "F.Fab")
		)
		(fp_poly
			(pts
				(xy -0.761746 0) (xy -2.285746 -0.762) (xy -2.285746 0.762)
			)
			(stroke
				(width 0)
				(type default)
			)
			(fill yes)
			(layer "F.Fab")
		)
		(pad "1" thru_hole circle
			(at 0 0 270)
			(size 1.0033 1.0033)
			(drill 0.249936)
			(layers "*.Cu" "*.Mask")
			(remove_unused_layers no)
			(net "TDR_DIFF_80_IN3_DP")
			(clearance 0.10795)
			(thermal_gap 0.10795)
			(padstack
				(mode front_inner_back)
				(layer "Inner"
					(shape circle)
					(size 0.8001 0.8001)
					(clearance 0.1524)
				)
				(layer "B.Cu"
					(shape circle)
					(size 1.0033 1.0033)
					(clearance 0.10795)
				)
			)
		)
		(pad "2" thru_hole circle
			(at 2.54 0 270)
			(size 1.9939 1.9939)
			(drill 0.249936)
			(layers "*.Cu" "*.Mask")
			(remove_unused_layers no)
			(net "T1_GND")
			(clearance 0.10795)
			(thermal_gap 0.10795)
			(padstack
				(mode front_inner_back)
				(layer "Inner"
					(shape circle)
					(size 0.8001 0.8001)
					(clearance 0.1524)
				)
				(layer "B.Cu"
					(shape circle)
					(size 1.9939 1.9939)
					(clearance 0.10795)
				)
			)
		)
		(pad "3" thru_hole circle
			(at 2.54 2.54 270)
			(size 1.9939 1.9939)
			(drill 0.249936)
			(layers "*.Cu" "*.Mask")
			(remove_unused_layers no)
			(net "T1_GND")
			(clearance 0.10795)
			(thermal_gap 0.10795)
			(padstack
				(mode front_inner_back)
				(layer "Inner"
					(shape circle)
					(size 0.8001 0.8001)
					(clearance 0.1524)
				)
				(layer "B.Cu"
					(shape circle)
					(size 1.9939 1.9939)
					(clearance 0.10795)
				)
			)
		)
		(pad "4" thru_hole circle
			(at 0 2.54 270)
			(size 1.0033 1.0033)
			(drill 0.249936)
			(layers "*.Cu" "*.Mask")
			(remove_unused_layers no)
			(net "TDR_DIFF_80_IN3_DN")
			(clearance 0.10795)
			(thermal_gap 0.10795)
			(padstack
				(mode front_inner_back)
				(layer "Inner"
					(shape circle)
					(size 0.8001 0.8001)
					(clearance 0.1524)
				)
				(layer "B.Cu"
					(shape circle)
					(size 1.0033 1.0033)
					(clearance 0.10795)
				)
			)
		)
	)
	(footprint ""
		(layer "F.Cu")
		(at 94.36481 -180.010562 -90)
		(property "Reference" "PC257"
			(at 0 0 270)
			(layer "F.SilkS")
			(hide yes)
			(effects
				(font
					(size 1.27 1.27)
				)
			)
		)
		(property "Value" ""
			(at 0 0 270)
			(layer "F.Fab")
			(effects
				(font
					(size 1.27 1.27)
				)
			)
		)
		(duplicate_pad_numbers_are_jumpers no)
		(fp_line
			(start -0.7874 0.4064)
			(end -0.7874 -0.4064)
			(stroke
				(width 0.1524)
				(type default)
			)
			(layer "F.SilkS")
		)
		(fp_line
			(start -0.278638 0.4064)
			(end -0.7874 0.4064)
			(stroke
				(width 0.1524)
				(type default)
			)
			(layer "F.SilkS")
		)
		(fp_line
			(start 0.7874 0.4064)
			(end 0.305562 0.4064)
			(stroke
				(width 0.1524)
				(type default)
			)
			(layer "F.SilkS")
		)
		(fp_line
			(start -0.7874 -0.4064)
			(end 0.7874 -0.4064)
			(stroke
				(width 0.1524)
				(type default)
			)
			(layer "F.SilkS")
		)
		(fp_line
			(start 0.7874 -0.4064)
			(end 0.7874 0.4064)
			(stroke
				(width 0.1524)
				(type default)
			)
			(layer "F.SilkS")
		)
		(fp_line
			(start -0.67945 0.3048)
			(end -0.67945 -0.305054)
			(stroke
				(width 0.1)
				(type default)
			)
			(layer "F.Fab")
		)
		(fp_line
			(start -0.12065 0.3048)
			(end -0.67945 0.3048)
			(stroke
				(width 0.1)
				(type default)
			)
			(layer "F.Fab")
		)
		(fp_line
			(start 0.120396 0.3048)
			(end 0.120396 0.2794)
			(stroke
				(width 0.1)
				(type default)
			)
			(layer "F.Fab")
		)
		(fp_line
			(start 0.67945 0.3048)
			(end 0.120396 0.3048)
			(stroke
				(width 0.1)
				(type default)
			)
			(layer "F.Fab")
		)
		(fp_line
			(start -0.12065 0.2794)
			(end -0.12065 0.3048)
			(stroke
				(width 0.1)
				(type default)
			)
			(layer "F.Fab")
		)
		(fp_line
			(start 0.120396 0.2794)
			(end -0.12065 0.2794)
			(stroke
				(width 0.1)
				(type default)
			)
			(layer "F.Fab")
		)
		(fp_line
			(start -0.12065 -0.2794)
			(end 0.12065 -0.2794)
			(stroke
				(width 0.1)
				(type default)
			)
			(layer "F.Fab")
		)
		(fp_line
			(start 0.12065 -0.2794)
			(end 0.12065 -0.3048)
			(stroke
				(width 0.1)
				(type default)
			)
			(layer "F.Fab")
		)
		(fp_line
			(start 0.12065 -0.3048)
			(end 0.67945 -0.3048)
			(stroke
				(width 0.1)
				(type default)
			)
			(layer "F.Fab")
		)
		(fp_line
			(start 0.67945 -0.3048)
			(end 0.67945 0.3048)
			(stroke
				(width 0.1)
				(type default)
			)
			(layer "F.Fab")
		)
		(fp_line
			(start -0.67945 -0.305054)
			(end -0.12065 -0.305054)
			(stroke
				(width 0.1)
				(type default)
			)
			(layer "F.Fab")
		)
		(fp_line
			(start -0.12065 -0.305054)
			(end -0.12065 -0.2794)
			(stroke
				(width 0.1)
				(type default)
			)
			(layer "F.Fab")
		)
		(pad "1" smd circle
			(at -0.40005 0 270)
			(size 0 0)
			(layers "F.Cu" "F.Mask" "F.Paste")
			(net "PVDDCR_CPU0_P1_VCC2")
		)
		(pad "2" smd circle
			(at 0.40005 0 270)
			(size 0 0)
			(layers "F.Cu" "F.Mask" "F.Paste")
			(net "GND")
		)
	)
	(footprint ""
		(layer "F.Cu")
		(at 213.9188 -122.460512)
		(property "Reference" "R956"
			(at 0 0 0)
			(layer "F.SilkS")
			(hide yes)
			(effects
				(font
					(size 1.27 1.27)
				)
			)
		)
		(property "Value" ""
			(at 0 0 0)
			(layer "F.Fab")
			(effects
				(font
					(size 1.27 1.27)
				)
			)
		)
		(duplicate_pad_numbers_are_jumpers no)
		(fp_line
			(start -0.7874 -0.4064)
			(end 0.7874 -0.4064)
			(stroke
				(width 0.1524)
				(type default)
			)
			(layer "F.SilkS")
		)
		(fp_line
			(start -0.7874 0.4064)
			(end -0.7874 -0.4064)
			(stroke
				(width 0.1524)
				(type default)
			)
			(layer "F.SilkS")
		)
		(fp_line
			(start 0.7874 -0.4064)
			(end 0.7874 0.4064)
			(stroke
				(width 0.1524)
				(type default)
			)
			(layer "F.SilkS")
		)
		(fp_line
			(start 0.7874 0.4064)
			(end -0.7874 0.4064)
			(stroke
				(width 0.1524)
				(type default)
			)
			(layer "F.SilkS")
		)
		(fp_line
			(start -0.67945 -0.305054)
			(end -0.12065 -0.305054)
			(stroke
				(width 0.1)
				(type default)
			)
			(layer "F.Fab")
		)
		(fp_line
			(start -0.67945 0.3048)
			(end -0.67945 -0.305054)
			(stroke
				(width 0.1)
				(type default)
			)
			(layer "F.Fab")
		)
		(fp_line
			(start -0.12065 -0.305054)
			(end -0.12065 -0.2794)
			(stroke
				(width 0.1)
				(type default)
			)
			(layer "F.Fab")
		)
		(fp_line
			(start -0.12065 -0.2794)
			(end 0.12065 -0.2794)
			(stroke
				(width 0.1)
				(type default)
			)
			(layer "F.Fab")
		)
		(fp_line
			(start -0.12065 0.2794)
			(end -0.12065 0.3048)
			(stroke
				(width 0.1)
				(type default)
			)
			(layer "F.Fab")
		)
		(fp_line
			(start -0.12065 0.3048)
			(end -0.67945 0.3048)
			(stroke
				(width 0.1)
				(type default)
			)
			(layer "F.Fab")
		)
		(fp_line
			(start 0.120396 0.2794)
			(end -0.12065 0.2794)
			(stroke
				(width 0.1)
				(type default)
			)
			(layer "F.Fab")
		)
		(fp_line
			(start 0.120396 0.3048)
			(end 0.120396 0.2794)
			(stroke
				(width 0.1)
				(type default)
			)
			(layer "F.Fab")
		)
		(fp_line
			(start 0.12065 -0.3048)
			(end 0.67945 -0.3048)
			(stroke
				(width 0.1)
				(type default)
			)
			(layer "F.Fab")
		)
		(fp_line
			(start 0.12065 -0.2794)
			(end 0.12065 -0.3048)
			(stroke
				(width 0.1)
				(type default)
			)
			(layer "F.Fab")
		)
		(fp_line
			(start 0.67945 -0.3048)
			(end 0.67945 0.3048)
			(stroke
				(width 0.1)
				(type default)
			)
			(layer "F.Fab")
		)
		(fp_line
			(start 0.67945 0.3048)
			(end 0.120396 0.3048)
			(stroke
				(width 0.1)
				(type default)
			)
			(layer "F.Fab")
		)
		(pad "1" smd circle
			(at -0.40005 0)
			(size 0 0)
			(layers "F.Cu" "F.Mask" "F.Paste")
			(net "RST_PERST_OCP_SFF_BUF2_N")
		)
		(pad "2" smd circle
			(at 0.40005 0)
			(size 0 0)
			(layers "F.Cu" "F.Mask" "F.Paste")
			(net "RST_PERST3_OCP_SFF_N")
		)
	)
	(footprint ""
		(layer "F.Cu")
		(at 301.800768 -147.909788 180)
		(property "Reference" "U105"
			(at -1.93294 -3.065272 90)
			(unlocked yes)
			(layer "F.SilkS")
			(effects
				(font
					(size 0.7874 0.5842)
					(thickness 0.1524)
				)
			)
		)
		(property "Value" ""
			(at 0 0 180)
			(layer "F.Fab")
			(effects
				(font
					(size 1.27 1.27)
				)
			)
		)
		(duplicate_pad_numbers_are_jumpers no)
		(fp_line
			(start 1.03378 1.284478)
			(end -1.03378 1.284478)
			(stroke
				(width 0.1524)
				(type default)
			)
			(layer "F.SilkS")
		)
		(fp_line
			(start 1.03378 -1.284478)
			(end 1.03378 1.284478)
			(stroke
				(width 0.1524)
				(type default)
			)
			(layer "F.SilkS")
		)
		(fp_line
			(start -1.03378 1.284478)
			(end -1.03378 -1.284478)
			(stroke
				(width 0.1524)
				(type default)
			)
			(layer "F.SilkS")
		)
		(fp_line
			(start -1.03378 -1.284478)
			(end 1.03378 -1.284478)
			(stroke
				(width 0.1524)
				(type default)
			)
			(layer "F.SilkS")
		)
		(fp_poly
			(pts
				(xy -1.806702 -1.052576) (xy -1.201674 -0.750062) (xy -1.806702 -0.447548)
			)
			(stroke
				(width 0)
				(type default)
			)
			(fill yes)
			(layer "F.SilkS")
		)
		(fp_line
			(start 0.774954 1.02489)
			(end -0.774954 1.02489)
			(stroke
				(width 0.1)
				(type default)
			)
			(layer "F.Fab")
		)
		(fp_line
			(start 0.774954 -1.02489)
			(end 0.774954 1.02489)
			(stroke
				(width 0.1)
				(type default)
			)
			(layer "F.Fab")
		)
		(fp_line
			(start -0.774954 1.02489)
			(end -0.774954 -1.02489)
			(stroke
				(width 0.1)
				(type default)
			)
			(layer "F.Fab")
		)
		(fp_line
			(start -0.774954 -1.02489)
			(end 0.774954 -1.02489)
			(stroke
				(width 0.1)
				(type default)
			)
			(layer "F.Fab")
		)
		(fp_poly
			(pts
				(xy -1.201674 -0.750062) (xy -1.806702 -0.447548) (xy -1.806702 -1.052576)
			)
			(stroke
				(width 0)
				(type default)
			)
			(fill yes)
			(layer "F.Fab")
		)
		(pad "1" smd rect
			(at -0.64008 -0.750062 270)
			(size 0.3048 0.5334)
			(layers "F.Cu" "F.Mask" "F.Paste")
			(net "I3C_0_SPD_DDRAF_CPU0_SCL")
		)
		(pad "2" smd rect
			(at -0.64008 -0.249936 270)
			(size 0.254 0.5334)
			(layers "F.Cu" "F.Mask" "F.Paste")
			(net "I3C_0_SPD_DDRAF_CPU0_SDA")
		)
		(pad "3" smd rect
			(at -0.64008 0.249936 270)
			(size 0.254 0.5334)
			(layers "F.Cu" "F.Mask" "F.Paste")
			(net "I3C_SCM_0_R_SCL")
		)
		(pad "4" smd rect
			(at -0.64008 0.750062 270)
			(size 0.3048 0.5334)
			(layers "F.Cu" "F.Mask" "F.Paste")
			(net "I3C_SCM_0_R_SDA")
		)
		(pad "5" smd rect
			(at 0 0.839978 180)
			(size 0.3302 0.635)
			(layers "F.Cu" "F.Mask" "F.Paste")
			(net "GND")
		)
		(pad "6" smd rect
			(at 0.64008 0.750062 270)
			(size 0.3048 0.5334)
			(layers "F.Cu" "F.Mask" "F.Paste")
			(net "FM_I3C_CPU0_MUX0_OE_N")
		)
		(pad "7" smd rect
			(at 0.64008 0.249936 270)
			(size 0.254 0.5334)
			(layers "F.Cu" "F.Mask" "F.Paste")
			(net "I3C_SPD_DDRAF_CPU0_LVC1_SDA")
		)
		(pad "8" smd rect
			(at 0.64008 -0.249936 270)
			(size 0.254 0.5334)
			(layers "F.Cu" "F.Mask" "F.Paste")
			(net "I3C_SPD_DDRAF_CPU0_LVC1_SCL")
		)
		(pad "9" smd rect
			(at 0.64008 -0.750062 270)
			(size 0.3048 0.5334)
			(layers "F.Cu" "F.Mask" "F.Paste")
			(net "FM_I3C_CPU0_MUX0_SEL")
		)
		(pad "10" smd rect
			(at 0 -0.839978 180)
			(size 0.3302 0.635)
			(layers "F.Cu" "F.Mask" "F.Paste")
			(net "P3V3_AUX")
		)
	)
)
